(kicad_pcb
	(version 20260206)
	(generator "pcbnew")
	(generator_version "10.0")
	(general
		(thickness 1.6)
		(legacy_teardrops no)
	)
	(paper "A4")
	(title_block
		(title "04192023_DAF0TMB3IC0_F0TG_MB_C_brd_V02_OCP.brd")
		(comment 1 "Grand Teton / footprint 3955 of 8354 (U25), pads 219-327 of 6102")
	)
	(layers
		(0 "F.Cu" signal "TOP")
		(4 "In1.Cu" signal "GND")
		(6 "In2.Cu" signal "IN1")
		(8 "In3.Cu" signal "GND1")
		(10 "In4.Cu" signal "IN2")
		(12 "In5.Cu" signal "GND2")
		(14 "In6.Cu" signal "IN3")
		(16 "In7.Cu" signal "GND3")
		(18 "In8.Cu" signal "VCC")
		(20 "In9.Cu" signal "VCC1")
		(22 "In10.Cu" signal "GND4")
		(24 "In11.Cu" signal "IN4")
		(26 "In12.Cu" signal "GND5")
		(28 "In13.Cu" signal "IN5")
		(30 "In14.Cu" signal "GND6")
		(32 "In15.Cu" signal "IN6")
		(34 "In16.Cu" signal "GND7")
		(2 "B.Cu" signal "BOTTOM")
		(9 "F.Adhes" user "F.Adhesive")
		(11 "B.Adhes" user "B.Adhesive")
		(13 "F.Paste" user "Package Geometry/Pastemask Top")
		(15 "B.Paste" user "Package Geometry/Pastemask Bottom")
		(5 "F.SilkS" user "Ref Des/Silkscreen Top")
		(7 "B.SilkS" user "Ref Des/Silkscreen Bottom")
		(1 "F.Mask" user "Board Geometry/Soldermask Top")
		(3 "B.Mask" user "Board Geometry/Soldermask Bottom")
		(17 "Dwgs.User" user "User.Drawings")
		(19 "Cmts.User" user "User.Comments")
		(21 "Eco1.User" user "User.Eco1")
		(23 "Eco2.User" user "User.Eco2")
		(25 "Edge.Cuts" user "Board Geometry/Outline")
		(27 "Margin" user)
		(31 "F.CrtYd" user "Package Geometry/Place Bound Top")
		(29 "B.CrtYd" user "Package Geometry/Place Bound Bottom")
		(35 "F.Fab" user "Ref Des/Assembly Top")
		(33 "B.Fab" user "Ref Des/Assembly Bottom")
	)
	(footprint ""
		(layer "F.Cu")
		(at 359.867962 -258.880102 180)
		(property "Reference" "U25"
			(at -45.78477 -62.086744 0)
			(unlocked yes)
			(layer "F.SilkS")
			(effects
				(font
					(size 0.7874 0.5842)
					(thickness 0.1524)
				)
			)
		)
		(property "Value" ""
			(at 0 0 180)
			(layer "F.Fab")
			(effects
				(font
					(size 1.27 1.27)
				)
			)
		)
		(duplicate_pad_numbers_are_jumpers no)
		(pad "AC13" smd circle
			(at -22.880066 -18.990056 180)
			(size 0.450088 0.450088)
			(layers "F.Cu" "F.Mask" "F.Paste")
			(net "GND")
		)
		(pad "AC14" smd circle
			(at -21.940012 -18.990056 180)
			(size 0.450088 0.450088)
			(layers "F.Cu" "F.Mask" "F.Paste")
			(net "M_H_CPU0_SA_DQ<23>")
		)
		(pad "AC15" smd circle
			(at -20.999958 -18.990056 180)
			(size 0.450088 0.450088)
			(layers "F.Cu" "F.Mask" "F.Paste")
			(net "GND")
		)
		(pad "AC16" smd circle
			(at -20.059904 -18.990056 180)
			(size 0.450088 0.450088)
			(layers "F.Cu" "F.Mask" "F.Paste")
			(net "M_J_CPU0_SA_DQ<24>")
		)
		(pad "AC17" smd circle
			(at -19.120104 -18.990056 180)
			(size 0.450088 0.450088)
			(layers "F.Cu" "F.Mask" "F.Paste")
			(net "M_J_CPU0_SA_DQ<23>")
		)
		(pad "AC18" smd circle
			(at -18.18005 -18.990056 180)
			(size 0.450088 0.450088)
			(layers "F.Cu" "F.Mask" "F.Paste")
			(net "PVDDCR_SOC_P0")
		)
		(pad "AC19" smd circle
			(at -17.239996 -18.990056 180)
			(size 0.450088 0.450088)
			(layers "F.Cu" "F.Mask" "F.Paste")
			(net "M_I_CPU0_SA_DQ<24>")
		)
		(pad "AC20" smd circle
			(at -16.299942 -18.990056 180)
			(size 0.450088 0.450088)
			(layers "F.Cu" "F.Mask" "F.Paste")
			(net "GND")
		)
		(pad "AC21" smd circle
			(at -15.359888 -18.990056 180)
			(size 0.450088 0.450088)
			(layers "F.Cu" "F.Mask" "F.Paste")
			(net "M_I_CPU0_SA_DQ<23>")
		)
		(pad "AC22" smd circle
			(at -14.420088 -18.990056 180)
			(size 0.450088 0.450088)
			(layers "F.Cu" "F.Mask" "F.Paste")
			(net "GND")
		)
		(pad "AC23" smd circle
			(at -13.480034 -18.990056 180)
			(size 0.450088 0.450088)
			(layers "F.Cu" "F.Mask" "F.Paste")
			(net "GMI_CPU1_G0_CPU0_G2_TX_DN<1>")
		)
		(pad "AC24" smd circle
			(at -12.53998 -18.990056 180)
			(size 0.450088 0.450088)
			(layers "F.Cu" "F.Mask" "F.Paste")
			(net "GMI_CPU1_G0_CPU0_G2_TX_DP<1>")
		)
		(pad "AC25" smd circle
			(at -11.599926 -18.990056 180)
			(size 0.450088 0.450088)
			(layers "F.Cu" "F.Mask" "F.Paste")
			(net "GND")
		)
		(pad "AC26" smd circle
			(at -10.659872 -18.990056 180)
			(size 0.450088 0.450088)
			(layers "F.Cu" "F.Mask" "F.Paste")
			(net "GMI_CPU1_G0_CPU0_G2_TX_DN<4>")
		)
		(pad "AC27" smd circle
			(at -9.720072 -18.990056 180)
			(size 0.450088 0.450088)
			(layers "F.Cu" "F.Mask" "F.Paste")
			(net "GMI_CPU1_G0_CPU0_G2_TX_DP<4>")
		)
		(pad "AC28" smd circle
			(at -8.780018 -18.990056 180)
			(size 0.450088 0.450088)
			(layers "F.Cu" "F.Mask" "F.Paste")
			(net "GND")
		)
		(pad "AC29" smd circle
			(at -7.839964 -18.990056 180)
			(size 0.450088 0.450088)
			(layers "F.Cu" "F.Mask" "F.Paste")
			(net "GMI_CPU1_G0_CPU0_G2_TX_DN<7>")
		)
		(pad "AC30" smd circle
			(at -6.89991 -18.990056 180)
			(size 0.450088 0.450088)
			(layers "F.Cu" "F.Mask" "F.Paste")
			(net "GMI_CPU1_G0_CPU0_G2_TX_DP<7>")
		)
		(pad "AC31" smd circle
			(at -5.96011 -18.990056 180)
			(size 0.450088 0.450088)
			(layers "F.Cu" "F.Mask" "F.Paste")
			(net "GND")
		)
		(pad "AC32" smd circle
			(at -5.020056 -18.990056 180)
			(size 0.450088 0.450088)
			(layers "F.Cu" "F.Mask" "F.Paste")
			(net "GMI_CPU1_G0_CPU0_G2_TX_DN<10>")
		)
		(pad "AC33" smd circle
			(at -4.080002 -18.990056 180)
			(size 0.450088 0.450088)
			(layers "F.Cu" "F.Mask" "F.Paste")
			(net "GMI_CPU1_G0_CPU0_G2_TX_DP<10>")
		)
		(pad "AC34" smd circle
			(at -3.139948 -18.990056 180)
			(size 0.450088 0.450088)
			(layers "F.Cu" "F.Mask" "F.Paste")
			(net "GND")
		)
		(pad "AC35" smd circle
			(at -2.199894 -18.990056 180)
			(size 0.450088 0.450088)
			(layers "F.Cu" "F.Mask" "F.Paste")
			(net "PVDDCR_CPU0_P0")
		)
		(pad "AC36" smd circle
			(at -1.260094 -18.990056 180)
			(size 0.450088 0.450088)
			(layers "F.Cu" "F.Mask" "F.Paste")
			(net "PVDDCR_CPU0_P0")
		)
		(pad "AC40" smd circle
			(at 1.560068 -18.990056 180)
			(size 0.450088 0.450088)
			(layers "F.Cu" "F.Mask" "F.Paste")
			(net "PVDDCR_CPU0_P0")
		)
		(pad "AC41" smd circle
			(at 2.500122 -18.990056 180)
			(size 0.450088 0.450088)
			(layers "F.Cu" "F.Mask" "F.Paste")
			(net "PVDDCR_CPU0_P0")
		)
		(pad "AC42" smd circle
			(at 3.439922 -18.990056 180)
			(size 0.450088 0.450088)
			(layers "F.Cu" "F.Mask" "F.Paste")
			(net "GND")
		)
		(pad "AC43" smd circle
			(at 4.379976 -18.990056 180)
			(size 0.450088 0.450088)
			(layers "F.Cu" "F.Mask" "F.Paste")
			(net "GMI_CPU0_G0_CPU1_G2_TX_DP<5>")
		)
		(pad "AC44" smd circle
			(at 5.32003 -18.990056 180)
			(size 0.450088 0.450088)
			(layers "F.Cu" "F.Mask" "F.Paste")
			(net "GMI_CPU0_G0_CPU1_G2_TX_DN<5>")
		)
		(pad "AC45" smd circle
			(at 6.260084 -18.990056 180)
			(size 0.450088 0.450088)
			(layers "F.Cu" "F.Mask" "F.Paste")
			(net "GND")
		)
		(pad "AC46" smd circle
			(at 7.199884 -18.990056 180)
			(size 0.450088 0.450088)
			(layers "F.Cu" "F.Mask" "F.Paste")
			(net "GMI_CPU0_G0_CPU1_G2_TX_DP<8>")
		)
		(pad "AC47" smd circle
			(at 8.139938 -18.990056 180)
			(size 0.450088 0.450088)
			(layers "F.Cu" "F.Mask" "F.Paste")
			(net "GMI_CPU0_G0_CPU1_G2_TX_DN<8>")
		)
		(pad "AC48" smd circle
			(at 9.079992 -18.990056 180)
			(size 0.450088 0.450088)
			(layers "F.Cu" "F.Mask" "F.Paste")
			(net "GND")
		)
		(pad "AC49" smd circle
			(at 10.020046 -18.990056 180)
			(size 0.450088 0.450088)
			(layers "F.Cu" "F.Mask" "F.Paste")
			(net "GMI_CPU0_G0_CPU1_G2_TX_DP<11>")
		)
		(pad "AC50" smd circle
			(at 10.9601 -18.990056 180)
			(size 0.450088 0.450088)
			(layers "F.Cu" "F.Mask" "F.Paste")
			(net "GMI_CPU0_G0_CPU1_G2_TX_DN<11>")
		)
		(pad "AC51" smd circle
			(at 11.8999 -18.990056 180)
			(size 0.450088 0.450088)
			(layers "F.Cu" "F.Mask" "F.Paste")
			(net "GND")
		)
		(pad "AC52" smd circle
			(at 12.839954 -18.990056 180)
			(size 0.450088 0.450088)
			(layers "F.Cu" "F.Mask" "F.Paste")
			(net "GMI_CPU0_G0_CPU1_G2_TX_DP<14>")
		)
		(pad "AC53" smd circle
			(at 13.780008 -18.990056 180)
			(size 0.450088 0.450088)
			(layers "F.Cu" "F.Mask" "F.Paste")
			(net "GMI_CPU0_G0_CPU1_G2_TX_DN<14>")
		)
		(pad "AC54" smd circle
			(at 14.720062 -18.990056 180)
			(size 0.450088 0.450088)
			(layers "F.Cu" "F.Mask" "F.Paste")
			(net "GND")
		)
		(pad "AC55" smd circle
			(at 15.660116 -18.990056 180)
			(size 0.450088 0.450088)
			(layers "F.Cu" "F.Mask" "F.Paste")
			(net "M_C_CPU0_SA_DQ<23>")
		)
		(pad "AC56" smd circle
			(at 16.599916 -18.990056 180)
			(size 0.450088 0.450088)
			(layers "F.Cu" "F.Mask" "F.Paste")
			(net "GND")
		)
		(pad "AC57" smd circle
			(at 17.53997 -18.990056 180)
			(size 0.450088 0.450088)
			(layers "F.Cu" "F.Mask" "F.Paste")
			(net "M_C_CPU0_SA_DQ<24>")
		)
		(pad "AC58" smd circle
			(at 18.480024 -18.990056 180)
			(size 0.450088 0.450088)
			(layers "F.Cu" "F.Mask" "F.Paste")
			(net "PVDDIO_P0")
		)
		(pad "AC59" smd circle
			(at 19.420078 -18.990056 180)
			(size 0.450088 0.450088)
			(layers "F.Cu" "F.Mask" "F.Paste")
			(net "M_D_CPU0_SA_DQ<23>")
		)
		(pad "AC60" smd circle
			(at 20.359878 -18.990056 180)
			(size 0.450088 0.450088)
			(layers "F.Cu" "F.Mask" "F.Paste")
			(net "M_D_CPU0_SA_DQ<24>")
		)
		(pad "AC61" smd circle
			(at 21.299932 -18.990056 180)
			(size 0.450088 0.450088)
			(layers "F.Cu" "F.Mask" "F.Paste")
			(net "GND")
		)
		(pad "AC62" smd circle
			(at 22.239986 -18.990056 180)
			(size 0.450088 0.450088)
			(layers "F.Cu" "F.Mask" "F.Paste")
			(net "M_B_CPU0_SA_DQ<23>")
		)
		(pad "AC63" smd circle
			(at 23.18004 -18.990056 180)
			(size 0.450088 0.450088)
			(layers "F.Cu" "F.Mask" "F.Paste")
			(net "GND")
		)
		(pad "AC64" smd circle
			(at 24.120094 -18.990056 180)
			(size 0.450088 0.450088)
			(layers "F.Cu" "F.Mask" "F.Paste")
			(net "M_B_CPU0_SA_DQ<24>")
		)
		(pad "AC65" smd circle
			(at 25.059894 -18.990056 180)
			(size 0.450088 0.450088)
			(layers "F.Cu" "F.Mask" "F.Paste")
			(net "PVDDIO_P0")
		)
		(pad "AC66" smd circle
			(at 25.999948 -18.990056 180)
			(size 0.450088 0.450088)
			(layers "F.Cu" "F.Mask" "F.Paste")
			(net "M_F_CPU0_SA_DQ<23>")
		)
		(pad "AC67" smd circle
			(at 26.940002 -18.990056 180)
			(size 0.450088 0.450088)
			(layers "F.Cu" "F.Mask" "F.Paste")
			(net "M_F_CPU0_SA_DQ<24>")
		)
		(pad "AC68" smd circle
			(at 27.880056 -18.990056 180)
			(size 0.450088 0.450088)
			(layers "F.Cu" "F.Mask" "F.Paste")
			(net "GND")
		)
		(pad "AC69" smd circle
			(at 28.82011 -18.990056 180)
			(size 0.450088 0.450088)
			(layers "F.Cu" "F.Mask" "F.Paste")
			(net "M_E_CPU0_SA_DQ<23>")
		)
		(pad "AC70" smd circle
			(at 29.75991 -18.990056 180)
			(size 0.450088 0.450088)
			(layers "F.Cu" "F.Mask" "F.Paste")
			(net "GND")
		)
		(pad "AC71" smd circle
			(at 30.699964 -18.990056 180)
			(size 0.450088 0.450088)
			(layers "F.Cu" "F.Mask" "F.Paste")
			(net "M_E_CPU0_SA_DQ<24>")
		)
		(pad "AC72" smd circle
			(at 31.640018 -18.990056 180)
			(size 0.450088 0.450088)
			(layers "F.Cu" "F.Mask" "F.Paste")
			(net "PVDDIO_P0")
		)
		(pad "AC73" smd circle
			(at 32.580072 -18.990056 180)
			(size 0.450088 0.450088)
			(layers "F.Cu" "F.Mask" "F.Paste")
			(net "M_A_CPU0_SA_DQ<23>")
		)
		(pad "AC74" smd circle
			(at 33.519872 -18.990056 180)
			(size 0.450088 0.450088)
			(layers "F.Cu" "F.Mask" "F.Paste")
			(net "M_A_CPU0_SA_DQ<24>")
		)
		(pad "AC75" smd circle
			(at 34.459926 -18.990056 180)
			(size 0.450088 0.450088)
			(layers "F.Cu" "F.Mask" "F.Paste")
			(net "GND")
		)
		(pad "AD2" smd circle
			(at -33.690052 -18.18005 180)
			(size 0.450088 0.450088)
			(layers "F.Cu" "F.Mask" "F.Paste")
			(net "M_G_CPU0_SA_DQ<26>")
		)
		(pad "AD3" smd circle
			(at -32.749998 -18.18005 180)
			(size 0.450088 0.450088)
			(layers "F.Cu" "F.Mask" "F.Paste")
			(net "GND")
		)
		(pad "AD4" smd circle
			(at -31.809944 -18.18005 180)
			(size 0.450088 0.450088)
			(layers "F.Cu" "F.Mask" "F.Paste")
			(net "M_G_CPU0_SA_DQ<25>")
		)
		(pad "AD5" smd circle
			(at -30.86989 -18.18005 180)
			(size 0.450088 0.450088)
			(layers "F.Cu" "F.Mask" "F.Paste")
			(net "GND")
		)
		(pad "AD6" smd circle
			(at -29.93009 -18.18005 180)
			(size 0.450088 0.450088)
			(layers "F.Cu" "F.Mask" "F.Paste")
			(net "M_K_CPU0_SA_DQ<26>")
		)
		(pad "AD7" smd circle
			(at -28.990036 -18.18005 180)
			(size 0.450088 0.450088)
			(layers "F.Cu" "F.Mask" "F.Paste")
			(net "M_K_CPU0_SA_DQ<25>")
		)
		(pad "AD8" smd circle
			(at -28.049982 -18.18005 180)
			(size 0.450088 0.450088)
			(layers "F.Cu" "F.Mask" "F.Paste")
			(net "GND")
		)
		(pad "AD9" smd circle
			(at -27.109928 -18.18005 180)
			(size 0.450088 0.450088)
			(layers "F.Cu" "F.Mask" "F.Paste")
			(net "M_L_CPU0_SA_DQ<26>")
		)
		(pad "AD10" smd circle
			(at -26.170128 -18.18005 180)
			(size 0.450088 0.450088)
			(layers "F.Cu" "F.Mask" "F.Paste")
			(net "GND")
		)
		(pad "AD11" smd circle
			(at -25.230074 -18.18005 180)
			(size 0.450088 0.450088)
			(layers "F.Cu" "F.Mask" "F.Paste")
			(net "M_L_CPU0_SA_DQ<25>")
		)
		(pad "AD12" smd circle
			(at -24.29002 -18.18005 180)
			(size 0.450088 0.450088)
			(layers "F.Cu" "F.Mask" "F.Paste")
			(net "GND")
		)
		(pad "AD13" smd circle
			(at -23.349966 -18.18005 180)
			(size 0.450088 0.450088)
			(layers "F.Cu" "F.Mask" "F.Paste")
			(net "M_H_CPU0_SA_DQ<26>")
		)
		(pad "AD14" smd circle
			(at -22.409912 -18.18005 180)
			(size 0.450088 0.450088)
			(layers "F.Cu" "F.Mask" "F.Paste")
			(net "M_H_CPU0_SA_DQ<25>")
		)
		(pad "AD15" smd circle
			(at -21.470112 -18.18005 180)
			(size 0.450088 0.450088)
			(layers "F.Cu" "F.Mask" "F.Paste")
			(net "GND")
		)
		(pad "AD16" smd circle
			(at -20.530058 -18.18005 180)
			(size 0.450088 0.450088)
			(layers "F.Cu" "F.Mask" "F.Paste")
			(net "M_J_CPU0_SA_DQ<26>")
		)
		(pad "AD17" smd circle
			(at -19.590004 -18.18005 180)
			(size 0.450088 0.450088)
			(layers "F.Cu" "F.Mask" "F.Paste")
			(net "GND")
		)
		(pad "AD18" smd circle
			(at -18.64995 -18.18005 180)
			(size 0.450088 0.450088)
			(layers "F.Cu" "F.Mask" "F.Paste")
			(net "M_J_CPU0_SA_DQ<25>")
		)
		(pad "AD19" smd circle
			(at -17.709896 -18.18005 180)
			(size 0.450088 0.450088)
			(layers "F.Cu" "F.Mask" "F.Paste")
			(net "GND")
		)
		(pad "AD20" smd circle
			(at -16.770096 -18.18005 180)
			(size 0.450088 0.450088)
			(layers "F.Cu" "F.Mask" "F.Paste")
			(net "M_I_CPU0_SA_DQ<26>")
		)
		(pad "AD21" smd circle
			(at -15.830042 -18.18005 180)
			(size 0.450088 0.450088)
			(layers "F.Cu" "F.Mask" "F.Paste")
			(net "M_I_CPU0_SA_DQ<25>")
		)
		(pad "AD22" smd circle
			(at -14.889988 -18.18005 180)
			(size 0.450088 0.450088)
			(layers "F.Cu" "F.Mask" "F.Paste")
			(net "PVDDCR_SOC_P0")
		)
		(pad "AD23" smd circle
			(at -13.949934 -18.18005 180)
			(size 0.450088 0.450088)
			(layers "F.Cu" "F.Mask" "F.Paste")
			(net "GND")
		)
		(pad "AD24" smd circle
			(at -13.00988 -18.18005 180)
			(size 0.450088 0.450088)
			(layers "F.Cu" "F.Mask" "F.Paste")
			(net "GND")
		)
		(pad "AD25" smd circle
			(at -12.07008 -18.18005 180)
			(size 0.450088 0.450088)
			(layers "F.Cu" "F.Mask" "F.Paste")
			(net "GND")
		)
		(pad "AD26" smd circle
			(at -11.130026 -18.18005 180)
			(size 0.450088 0.450088)
			(layers "F.Cu" "F.Mask" "F.Paste")
			(net "GND")
		)
		(pad "AD27" smd circle
			(at -10.189972 -18.18005 180)
			(size 0.450088 0.450088)
			(layers "F.Cu" "F.Mask" "F.Paste")
			(net "GND")
		)
		(pad "AD28" smd circle
			(at -9.249918 -18.18005 180)
			(size 0.450088 0.450088)
			(layers "F.Cu" "F.Mask" "F.Paste")
			(net "GND")
		)
		(pad "AD29" smd circle
			(at -8.310118 -18.18005 180)
			(size 0.450088 0.450088)
			(layers "F.Cu" "F.Mask" "F.Paste")
			(net "GND")
		)
		(pad "AD30" smd circle
			(at -7.370064 -18.18005 180)
			(size 0.450088 0.450088)
			(layers "F.Cu" "F.Mask" "F.Paste")
			(net "GND")
		)
		(pad "AD31" smd circle
			(at -6.43001 -18.18005 180)
			(size 0.450088 0.450088)
			(layers "F.Cu" "F.Mask" "F.Paste")
			(net "GND")
		)
		(pad "AD32" smd circle
			(at -5.489956 -18.18005 180)
			(size 0.450088 0.450088)
			(layers "F.Cu" "F.Mask" "F.Paste")
			(net "GND")
		)
		(pad "AD33" smd circle
			(at -4.549902 -18.18005 180)
			(size 0.450088 0.450088)
			(layers "F.Cu" "F.Mask" "F.Paste")
			(net "GND")
		)
		(pad "AD34" smd circle
			(at -3.610102 -18.18005 180)
			(size 0.450088 0.450088)
			(layers "F.Cu" "F.Mask" "F.Paste")
			(net "GND")
		)
		(pad "AD35" smd circle
			(at -2.670048 -18.18005 180)
			(size 0.450088 0.450088)
			(layers "F.Cu" "F.Mask" "F.Paste")
			(net "GMI_CPU1_G0_CPU0_G2_TX_DN<14>")
		)
		(pad "AD36" smd circle
			(at -1.729994 -18.18005 180)
			(size 0.450088 0.450088)
			(layers "F.Cu" "F.Mask" "F.Paste")
			(net "GMI_CPU1_G0_CPU0_G2_TX_DP<14>")
		)
		(pad "AD37" smd circle
			(at -0.78994 -18.18005 180)
			(size 0.450088 0.450088)
			(layers "F.Cu" "F.Mask" "F.Paste")
			(net "GND")
		)
		(pad "AD39" smd circle
			(at 1.089914 -18.18005 180)
			(size 0.450088 0.450088)
			(layers "F.Cu" "F.Mask" "F.Paste")
			(net "GND")
		)
		(pad "AD40" smd circle
			(at 2.029968 -18.18005 180)
			(size 0.450088 0.450088)
			(layers "F.Cu" "F.Mask" "F.Paste")
			(net "GMI_CPU0_G0_CPU1_G2_TX_DP<1>")
		)
		(pad "AD41" smd circle
			(at 2.970022 -18.18005 180)
			(size 0.450088 0.450088)
			(layers "F.Cu" "F.Mask" "F.Paste")
			(net "GMI_CPU0_G0_CPU1_G2_TX_DN<1>")
		)
		(pad "AD42" smd circle
			(at 3.910076 -18.18005 180)
			(size 0.450088 0.450088)
			(layers "F.Cu" "F.Mask" "F.Paste")
			(net "GND")
		)
		(pad "AD43" smd circle
			(at 4.849876 -18.18005 180)
			(size 0.450088 0.450088)
			(layers "F.Cu" "F.Mask" "F.Paste")
			(net "GND")
		)
		(pad "AD44" smd circle
			(at 5.78993 -18.18005 180)
			(size 0.450088 0.450088)
			(layers "F.Cu" "F.Mask" "F.Paste")
			(net "GND")
		)
		(pad "AD45" smd circle
			(at 6.729984 -18.18005 180)
			(size 0.450088 0.450088)
			(layers "F.Cu" "F.Mask" "F.Paste")
			(net "GND")
		)
		(pad "AD46" smd circle
			(at 7.670038 -18.18005 180)
			(size 0.450088 0.450088)
			(layers "F.Cu" "F.Mask" "F.Paste")
			(net "GND")
		)
		(pad "AD47" smd circle
			(at 8.610092 -18.18005 180)
			(size 0.450088 0.450088)
			(layers "F.Cu" "F.Mask" "F.Paste")
			(net "GND")
		)
		(pad "AD48" smd circle
			(at 9.549892 -18.18005 180)
			(size 0.450088 0.450088)
			(layers "F.Cu" "F.Mask" "F.Paste")
			(net "GND")
		)
		(pad "AD49" smd circle
			(at 10.489946 -18.18005 180)
			(size 0.450088 0.450088)
			(layers "F.Cu" "F.Mask" "F.Paste")
			(net "GND")
		)
		(pad "AD50" smd circle
			(at 11.43 -18.18005 180)
			(size 0.450088 0.450088)
			(layers "F.Cu" "F.Mask" "F.Paste")
			(net "GND")
		)
		(pad "AD51" smd circle
			(at 12.370054 -18.18005 180)
			(size 0.450088 0.450088)
			(layers "F.Cu" "F.Mask" "F.Paste")
			(net "GND")
		)
	)
)
